# BASEBOARD_FAB2 (Tioga Pass) — schematic netlist excerpt (pin names and nets, part order shuffled) for the footprints in the layout excerpt that follows; sources: Cadence DE-HDL packaged netlist, KiCad conversion of Wiwynn_Tioga_Pass_MB.brd

J6E1  SCONN120_H61426002  CONN  pkg SM  page 194
  IOA1  = PVCCMCP_CPU0
  IOA2  = PVCCMCP_CPU0
  IOA3  = PVCCMCP_CPU0
  IOA4  = VSENSE_PVCCMCP_CPU0_SKT_VSEN
  IOA5  = PVCCMCP_CPU0
  IOA6  = PVCCMCP_CPU0
  IOA7  = PVCCMCP_CPU0
  IOA8  = PVCCMCP_CPU0
  IOA9  = PVCCMCP_CPU0
  IOA10  = PVCCMCP_CPU0
  IOA11  = PVCCMCP_CPU0
  IOA12  = PVCCMCP_CPU0
  IOA13  = PVCCMCP_CPU0
  IOA14  = PVCCMCP_CPU0
  IOA15  = PVCCMCP_CPU0
  IOA16  = PVCCMCP_CPU0
  IOA17  = PVCCMCP_CPU0
  IOA18  = PVCCMCP_CPU0
  IOA19  = GND
  IOA20  = GND
  IOB1  = PVCCMCP_CPU0
  IOB2  = PVCCMCP_CPU0
  IOB3  = PVCCMCP_CPU0
  IOB4  = VSENSE_PVCCMCP_CPU0_SKT_VRTN
  IOB5  = PVCCMCP_CPU0
  IOB6  = PVCCMCP_CPU0
  IOB7  = PVCCMCP_CPU0
  IOB8  = PVCCMCP_CPU0
  IOB9  = PVCCMCP_CPU0
  IOB10  = PVCCMCP_CPU0
  IOB11  = PVCCMCP_CPU0
  IOB12  = PVCCMCP_CPU0
  IOB13  = PVCCMCP_CPU0
  IOB14  = PVCCMCP_CPU0
  IOB15  = PVCCMCP_CPU0
  IOB16  = PVCCMCP_CPU0
  IOB17  = PVCCMCP_CPU0
  IOB18  = PVCCMCP_CPU0
  IOB19  = GND
  IOB20  = GND
  IOC1  = PVCCMCP_CPU0
  IOC2  = PVCCMCP_CPU0
  IOC3  = PVCCMCP_CPU0
  IOC4  = PVCCMCP_CPU0
  IOC5  = PVCCMCP_CPU0
  IOC6  = PVCCMCP_CPU0
  IOC7  = PVCCMCP_CPU0
  IOC8  = PVCCMCP_CPU0
  IOC9  = PVCCMCP_CPU0
  IOC10  = PVCCMCP_CPU0
  IOC11  = PVCCMCP_CPU0
  IOC12  = PVCCMCP_CPU0
  IOC13  = PVCCMCP_CPU0
  IOC14  = PVCCMCP_CPU0
  IOC15  = PVCCMCP_CPU0
  IOC16  = PVCCMCP_CPU0
  IOC17  = PVCCMCP_CPU0
  IOC18  = PVCCMCP_CPU0
  IOC19  = GND
  IOC20  = GND
  IOD1  = VSENSE_P1V8MCP_CPU0_SKT_VSEN
  IOD2  = VSENSE_P1V8MCP_CPU0_SKT_VRTN
  IOD3  = P1V8_MCP_CPU0
  IOD4  = GND
  IOD5  = GND
  IOD6  = GND
  IOD7  = GND
  IOD8  = GND
  IOD9  = GND
  IOD10  = GND
  IOD11  = GND
  IOD12  = GND
  IOD13  = GND
  IOD14  = GND
  IOD15  = GND
  IOD16  = GND
  IOD17  = GND
  IOD18  = GND
  IOD19  = GND
  IOD20  = GND
  IOE1  = P1V8_MCP_CPU0
  IOE2  = P1V8_MCP_CPU0
  IOE3  = P1V8_MCP_CPU0
  IOE4  = GND
  IOE5  = CLK_322M_156M_CPU0_OSC_VRM_DP
  IOE6  = GND
  IOE7  = GND
  IOE8  = GND
  IOE9  = GND
  IOE10  = GND
  IOE11  = GND
  IOE12  = GND
  IOE13  = GND
  IOE14  = GND
  IOE15  = GND
  IOE16  = GND
  IOE17  = GND
  IOE18  = GND
  IOE19  = GND
  IOE20  = GND
  IOF1  = P1V8_MCP_CPU0
  IOF2  = P1V8_MCP_CPU0
  IOF3  = P1V8_MCP_CPU0
  IOF4  = GND
  IOF5  = CLK_322M_156M_CPU0_OSC_VRM_DN
  IOF6  = GND
  IOF7  = GND
  IOF8  = GND
  IOF9  = GND
  IOF10  = GND
  IOF11  = GND
  IOF12  = GND
  IOF13  = GND
  IOF14  = GND
  IOF15  = GND
  IOF16  = GND
  IOF17  = GND
  IOF18  = GND
  IOF19  = GND
  IOF20  = GND

(kicad_pcb
	(version 20260206)
	(generator "pcbnew")
	(generator_version "10.0")
	(general
		(thickness 1.6)
		(legacy_teardrops no)
	)
	(paper "A4")
	(title_block
		(title "Wiwynn_Tioga_Pass_MB.brd")
		(comment 1 "Tioga Pass / footprint 587 of 4770 (J6E1), pads 1-49 of 122")
	)
	(layers
		(0 "F.Cu" signal "TOP")
		(4 "In1.Cu" signal "L2GND")
		(6 "In2.Cu" signal "L3")
		(8 "In3.Cu" signal "L4GND")
		(10 "In4.Cu" signal "L5")
		(12 "In5.Cu" signal "L6GND")
		(14 "In6.Cu" signal "L7VCC")
		(16 "In7.Cu" signal "L8VCC")
		(18 "In8.Cu" signal "L9GND")
		(20 "In9.Cu" signal "L10")
		(22 "In10.Cu" signal "L11GND")
		(24 "In11.Cu" signal "L12")
		(26 "In12.Cu" signal "L13GND")
		(2 "B.Cu" signal "BOTTOM")
		(9 "F.Adhes" user "F.Adhesive")
		(11 "B.Adhes" user "B.Adhesive")
		(13 "F.Paste" user "Package Geometry/Pastemask Top")
		(15 "B.Paste" user "Package Geometry/Pastemask Bottom")
		(5 "F.SilkS" user "Ref Des/Silkscreen Top")
		(7 "B.SilkS" user "Ref Des/Silkscreen Bottom")
		(1 "F.Mask" user "Board Geometry/Soldermask Top")
		(3 "B.Mask" user "Board Geometry/Soldermask Bottom")
		(17 "Dwgs.User" user "User.Drawings")
		(19 "Cmts.User" user "User.Comments")
		(21 "Eco1.User" user "User.Eco1")
		(23 "Eco2.User" user "User.Eco2")
		(25 "Edge.Cuts" user "Board Geometry/Outline")
		(27 "Margin" user)
		(31 "F.CrtYd" user "Package Geometry/Place Bound Top")
		(29 "B.CrtYd" user "Package Geometry/Place Bound Bottom")
		(35 "F.Fab" user "Ref Des/Assembly Top")
		(33 "B.Fab" user "Ref Des/Assembly Bottom")
	)
	(footprint ""
		(layer "F.Cu")
		(at 329.594972 -43.80103 90)
		(property "Reference" "J6E1"
			(at -3.59283 -5.018024 90)
			(unlocked yes)
			(layer "F.SilkS")
			(effects
				(font
					(size 0.7874 0.5842)
					(thickness 0.1524)
				)
			)
		)
		(property "Value" ""
			(at 0 0 90)
			(layer "F.Fab")
			(effects
				(font
					(size 1.27 1.27)
				)
			)
		)
		(duplicate_pad_numbers_are_jumpers no)
		(pad "" np_thru_hole circle
			(at -3.175 26.5557 90)
			(size 0.254 0.254)
			(drill 1.27)
			(layers "*.Cu" "*.Mask")
			(clearance 0.8255)
			(thermal_gap 0.8255)
		)
		(pad "" np_thru_hole circle
			(at -0.127 -2.4257 90)
			(size 0.254 0.254)
			(drill 1.27)
			(layers "*.Cu" "*.Mask")
			(clearance 0.8255)
			(thermal_gap 0.8255)
		)
		(pad "A1" smd circle
			(at 0 0 90)
			(size 0.635 0.635)
			(layers "F.Cu" "F.Mask" "F.Paste")
			(net "PVCCMCP_CPU0")
		)
		(pad "A2" smd circle
			(at 0 1.27 90)
			(size 0.635 0.635)
			(layers "F.Cu" "F.Mask" "F.Paste")
			(net "PVCCMCP_CPU0")
		)
		(pad "A3" smd circle
			(at 0 2.54 90)
			(size 0.635 0.635)
			(layers "F.Cu" "F.Mask" "F.Paste")
			(net "PVCCMCP_CPU0")
		)
		(pad "A4" smd circle
			(at 0 3.81 90)
			(size 0.635 0.635)
			(layers "F.Cu" "F.Mask" "F.Paste")
			(net "VSENSE_PVCCMCP_CPU0_SKT_VSEN")
		)
		(pad "A5" smd circle
			(at 0 5.08 90)
			(size 0.635 0.635)
			(layers "F.Cu" "F.Mask" "F.Paste")
			(net "PVCCMCP_CPU0")
		)
		(pad "A6" smd circle
			(at 0 6.35 90)
			(size 0.635 0.635)
			(layers "F.Cu" "F.Mask" "F.Paste")
			(net "PVCCMCP_CPU0")
		)
		(pad "A7" smd circle
			(at 0 7.62 90)
			(size 0.635 0.635)
			(layers "F.Cu" "F.Mask" "F.Paste")
			(net "PVCCMCP_CPU0")
		)
		(pad "A8" smd circle
			(at 0 8.89 90)
			(size 0.635 0.635)
			(layers "F.Cu" "F.Mask" "F.Paste")
			(net "PVCCMCP_CPU0")
		)
		(pad "A9" smd circle
			(at 0 10.16 90)
			(size 0.635 0.635)
			(layers "F.Cu" "F.Mask" "F.Paste")
			(net "PVCCMCP_CPU0")
		)
		(pad "A10" smd circle
			(at 0 11.43 90)
			(size 0.635 0.635)
			(layers "F.Cu" "F.Mask" "F.Paste")
			(net "PVCCMCP_CPU0")
		)
		(pad "A11" smd circle
			(at 0 12.7 90)
			(size 0.635 0.635)
			(layers "F.Cu" "F.Mask" "F.Paste")
			(net "PVCCMCP_CPU0")
		)
		(pad "A12" smd circle
			(at 0 13.97 90)
			(size 0.635 0.635)
			(layers "F.Cu" "F.Mask" "F.Paste")
			(net "PVCCMCP_CPU0")
		)
		(pad "A13" smd circle
			(at 0 15.24 90)
			(size 0.635 0.635)
			(layers "F.Cu" "F.Mask" "F.Paste")
			(net "PVCCMCP_CPU0")
		)
		(pad "A14" smd circle
			(at 0 16.51 90)
			(size 0.635 0.635)
			(layers "F.Cu" "F.Mask" "F.Paste")
			(net "PVCCMCP_CPU0")
		)
		(pad "A15" smd circle
			(at 0 17.78 90)
			(size 0.635 0.635)
			(layers "F.Cu" "F.Mask" "F.Paste")
			(net "PVCCMCP_CPU0")
		)
		(pad "A16" smd circle
			(at 0 19.05 90)
			(size 0.635 0.635)
			(layers "F.Cu" "F.Mask" "F.Paste")
			(net "PVCCMCP_CPU0")
		)
		(pad "A17" smd circle
			(at 0 20.32 90)
			(size 0.635 0.635)
			(layers "F.Cu" "F.Mask" "F.Paste")
			(net "PVCCMCP_CPU0")
		)
		(pad "A18" smd circle
			(at 0 21.59 90)
			(size 0.635 0.635)
			(layers "F.Cu" "F.Mask" "F.Paste")
			(net "PVCCMCP_CPU0")
		)
		(pad "A19" smd circle
			(at 0 22.86 90)
			(size 0.635 0.635)
			(layers "F.Cu" "F.Mask" "F.Paste")
			(net "GND")
		)
		(pad "A20" smd circle
			(at 0 24.13 90)
			(size 0.635 0.635)
			(layers "F.Cu" "F.Mask" "F.Paste")
			(net "GND")
		)
		(pad "B1" smd circle
			(at -1.27 0 90)
			(size 0.635 0.635)
			(layers "F.Cu" "F.Mask" "F.Paste")
			(net "PVCCMCP_CPU0")
		)
		(pad "B2" smd circle
			(at -1.27 1.27 90)
			(size 0.635 0.635)
			(layers "F.Cu" "F.Mask" "F.Paste")
			(net "PVCCMCP_CPU0")
		)
		(pad "B3" smd circle
			(at -1.27 2.54 90)
			(size 0.635 0.635)
			(layers "F.Cu" "F.Mask" "F.Paste")
			(net "PVCCMCP_CPU0")
		)
		(pad "B4" smd circle
			(at -1.27 3.81 90)
			(size 0.635 0.635)
			(layers "F.Cu" "F.Mask" "F.Paste")
			(net "VSENSE_PVCCMCP_CPU0_SKT_VRTN")
		)
		(pad "B5" smd circle
			(at -1.27 5.08 90)
			(size 0.635 0.635)
			(layers "F.Cu" "F.Mask" "F.Paste")
			(net "PVCCMCP_CPU0")
		)
		(pad "B6" smd circle
			(at -1.27 6.35 90)
			(size 0.635 0.635)
			(layers "F.Cu" "F.Mask" "F.Paste")
			(net "PVCCMCP_CPU0")
		)
		(pad "B7" smd circle
			(at -1.27 7.62 90)
			(size 0.635 0.635)
			(layers "F.Cu" "F.Mask" "F.Paste")
			(net "PVCCMCP_CPU0")
		)
		(pad "B8" smd circle
			(at -1.27 8.89 90)
			(size 0.635 0.635)
			(layers "F.Cu" "F.Mask" "F.Paste")
			(net "PVCCMCP_CPU0")
		)
		(pad "B9" smd circle
			(at -1.27 10.16 90)
			(size 0.635 0.635)
			(layers "F.Cu" "F.Mask" "F.Paste")
			(net "PVCCMCP_CPU0")
		)
		(pad "B10" smd circle
			(at -1.27 11.43 90)
			(size 0.635 0.635)
			(layers "F.Cu" "F.Mask" "F.Paste")
			(net "PVCCMCP_CPU0")
		)
		(pad "B11" smd circle
			(at -1.27 12.7 90)
			(size 0.635 0.635)
			(layers "F.Cu" "F.Mask" "F.Paste")
			(net "PVCCMCP_CPU0")
		)
		(pad "B12" smd circle
			(at -1.27 13.97 90)
			(size 0.635 0.635)
			(layers "F.Cu" "F.Mask" "F.Paste")
			(net "PVCCMCP_CPU0")
		)
		(pad "B13" smd circle
			(at -1.27 15.24 90)
			(size 0.635 0.635)
			(layers "F.Cu" "F.Mask" "F.Paste")
			(net "PVCCMCP_CPU0")
		)
		(pad "B14" smd circle
			(at -1.27 16.51 90)
			(size 0.635 0.635)
			(layers "F.Cu" "F.Mask" "F.Paste")
			(net "PVCCMCP_CPU0")
		)
		(pad "B15" smd circle
			(at -1.27 17.78 90)
			(size 0.635 0.635)
			(layers "F.Cu" "F.Mask" "F.Paste")
			(net "PVCCMCP_CPU0")
		)
		(pad "B16" smd circle
			(at -1.27 19.05 90)
			(size 0.635 0.635)
			(layers "F.Cu" "F.Mask" "F.Paste")
			(net "PVCCMCP_CPU0")
		)
		(pad "B17" smd circle
			(at -1.27 20.32 90)
			(size 0.635 0.635)
			(layers "F.Cu" "F.Mask" "F.Paste")
			(net "PVCCMCP_CPU0")
		)
		(pad "B18" smd circle
			(at -1.27 21.59 90)
			(size 0.635 0.635)
			(layers "F.Cu" "F.Mask" "F.Paste")
			(net "PVCCMCP_CPU0")
		)
		(pad "B19" smd circle
			(at -1.27 22.86 90)
			(size 0.635 0.635)
			(layers "F.Cu" "F.Mask" "F.Paste")
			(net "GND")
		)
		(pad "B20" smd circle
			(at -1.27 24.13 90)
			(size 0.635 0.635)
			(layers "F.Cu" "F.Mask" "F.Paste")
			(net "GND")
		)
		(pad "C1" smd circle
			(at -2.54 0 90)
			(size 0.635 0.635)
			(layers "F.Cu" "F.Mask" "F.Paste")
			(net "PVCCMCP_CPU0")
		)
		(pad "C2" smd circle
			(at -2.54 1.27 90)
			(size 0.635 0.635)
			(layers "F.Cu" "F.Mask" "F.Paste")
			(net "PVCCMCP_CPU0")
		)
		(pad "C3" smd circle
			(at -2.54 2.54 90)
			(size 0.635 0.635)
			(layers "F.Cu" "F.Mask" "F.Paste")
			(net "PVCCMCP_CPU0")
		)
		(pad "C4" smd circle
			(at -2.54 3.81 90)
			(size 0.635 0.635)
			(layers "F.Cu" "F.Mask" "F.Paste")
			(net "PVCCMCP_CPU0")
		)
		(pad "C5" smd circle
			(at -2.54 5.08 90)
			(size 0.635 0.635)
			(layers "F.Cu" "F.Mask" "F.Paste")
			(net "PVCCMCP_CPU0")
		)
		(pad "C6" smd circle
			(at -2.54 6.35 90)
			(size 0.635 0.635)
			(layers "F.Cu" "F.Mask" "F.Paste")
			(net "PVCCMCP_CPU0")
		)
		(pad "C7" smd circle
			(at -2.54 7.62 90)
			(size 0.635 0.635)
			(layers "F.Cu" "F.Mask" "F.Paste")
			(net "PVCCMCP_CPU0")
		)
	)
)
